(kicad_pcb
	(version 20260206)
	(generator "pcbnew")
	(generator_version "10.0")
	(general
		(thickness 1.6)
		(legacy_teardrops no)
	)
	(paper "A4")
	(title_block
		(title "04192023_DAF0TMB3IC0_F0TG_MB_C_brd_V02_OCP.brd")
		(comment 1 "Grand Teton / footprints 5739-5744 of 8354")
	)
	(layers
		(0 "F.Cu" signal "TOP")
		(4 "In1.Cu" signal "GND")
		(6 "In2.Cu" signal "IN1")
		(8 "In3.Cu" signal "GND1")
		(10 "In4.Cu" signal "IN2")
		(12 "In5.Cu" signal "GND2")
		(14 "In6.Cu" signal "IN3")
		(16 "In7.Cu" signal "GND3")
		(18 "In8.Cu" signal "VCC")
		(20 "In9.Cu" signal "VCC1")
		(22 "In10.Cu" signal "GND4")
		(24 "In11.Cu" signal "IN4")
		(26 "In12.Cu" signal "GND5")
		(28 "In13.Cu" signal "IN5")
		(30 "In14.Cu" signal "GND6")
		(32 "In15.Cu" signal "IN6")
		(34 "In16.Cu" signal "GND7")
		(2 "B.Cu" signal "BOTTOM")
		(9 "F.Adhes" user "F.Adhesive")
		(11 "B.Adhes" user "B.Adhesive")
		(13 "F.Paste" user "Package Geometry/Pastemask Top")
		(15 "B.Paste" user "Package Geometry/Pastemask Bottom")
		(5 "F.SilkS" user "Ref Des/Silkscreen Top")
		(7 "B.SilkS" user "Ref Des/Silkscreen Bottom")
		(1 "F.Mask" user "Board Geometry/Soldermask Top")
		(3 "B.Mask" user "Board Geometry/Soldermask Bottom")
		(17 "Dwgs.User" user "User.Drawings")
		(19 "Cmts.User" user "User.Comments")
		(21 "Eco1.User" user "User.Eco1")
		(23 "Eco2.User" user "User.Eco2")
		(25 "Edge.Cuts" user "Board Geometry/Outline")
		(27 "Margin" user)
		(31 "F.CrtYd" user "Package Geometry/Place Bound Top")
		(29 "B.CrtYd" user "Package Geometry/Place Bound Bottom")
		(35 "F.Fab" user "Ref Des/Assembly Top")
		(33 "B.Fab" user "Ref Des/Assembly Bottom")
	)
	(footprint ""
		(layer "B.Cu")
		(at 342.046052 -396.393162 -90)
		(property "Reference" "C608"
			(at 0 0 90)
			(layer "B.SilkS")
			(hide yes)
			(effects
				(font
					(size 1.27 1.27)
				)
				(justify mirror)
			)
		)
		(property "Value" ""
			(at 0 0 90)
			(layer "B.Fab")
			(effects
				(font
					(size 1.27 1.27)
				)
				(justify mirror)
			)
		)
		(duplicate_pad_numbers_are_jumpers no)
		(fp_line
			(start -0.299974 0.150114)
			(end 0.299974 0.150114)
			(stroke
				(width 0.1)
				(type default)
			)
			(layer "B.Fab")
		)
		(fp_line
			(start 0.299974 0.150114)
			(end 0.299974 -0.150114)
			(stroke
				(width 0.1)
				(type default)
			)
			(layer "B.Fab")
		)
		(fp_line
			(start -0.299974 -0.150114)
			(end -0.299974 0.150114)
			(stroke
				(width 0.1)
				(type default)
			)
			(layer "B.Fab")
		)
		(fp_line
			(start 0.299974 -0.150114)
			(end -0.299974 -0.150114)
			(stroke
				(width 0.1)
				(type default)
			)
			(layer "B.Fab")
		)
		(pad "1" smd rect
			(at 0.2667 0 90)
			(size 0.3048 0.381)
			(layers "B.Cu" "B.Mask" "B.Paste")
			(net "P0V9_CPU0_RT_2D")
		)
		(pad "2" smd rect
			(at -0.2667 0 90)
			(size 0.3048 0.381)
			(layers "B.Cu" "B.Mask" "B.Paste")
			(net "GND")
		)
	)
	(footprint ""
		(layer "B.Cu")
		(at 352.247454 -253.43231)
		(property "Reference" "C2582"
			(at 0 0 0)
			(layer "B.SilkS")
			(hide yes)
			(effects
				(font
					(size 1.27 1.27)
				)
				(justify mirror)
			)
		)
		(property "Value" ""
			(at 0 0 0)
			(layer "B.Fab")
			(effects
				(font
					(size 1.27 1.27)
				)
				(justify mirror)
			)
		)
		(duplicate_pad_numbers_are_jumpers no)
		(fp_line
			(start -0.7874 -0.4064)
			(end -0.7874 0.4064)
			(stroke
				(width 0.1524)
				(type default)
			)
			(layer "B.SilkS")
		)
		(fp_line
			(start -0.7874 0.4064)
			(end 0.7874 0.4064)
			(stroke
				(width 0.1524)
				(type default)
			)
			(layer "B.SilkS")
		)
		(fp_line
			(start 0.7874 -0.4064)
			(end -0.7874 -0.4064)
			(stroke
				(width 0.1524)
				(type default)
			)
			(layer "B.SilkS")
		)
		(fp_line
			(start 0.7874 0.4064)
			(end 0.7874 -0.4064)
			(stroke
				(width 0.1524)
				(type default)
			)
			(layer "B.SilkS")
		)
		(fp_line
			(start -0.67945 -0.3048)
			(end -0.67945 0.3048)
			(stroke
				(width 0.1)
				(type default)
			)
			(layer "B.Fab")
		)
		(fp_line
			(start -0.67945 0.3048)
			(end -0.120396 0.3048)
			(stroke
				(width 0.1)
				(type default)
			)
			(layer "B.Fab")
		)
		(fp_line
			(start -0.12065 -0.3048)
			(end -0.67945 -0.3048)
			(stroke
				(width 0.1)
				(type default)
			)
			(layer "B.Fab")
		)
		(fp_line
			(start -0.12065 -0.2794)
			(end -0.12065 -0.3048)
			(stroke
				(width 0.1)
				(type default)
			)
			(layer "B.Fab")
		)
		(fp_line
			(start -0.120396 0.2794)
			(end 0.12065 0.2794)
			(stroke
				(width 0.1)
				(type default)
			)
			(layer "B.Fab")
		)
		(fp_line
			(start -0.120396 0.3048)
			(end -0.120396 0.2794)
			(stroke
				(width 0.1)
				(type default)
			)
			(layer "B.Fab")
		)
		(fp_line
			(start 0.12065 -0.305054)
			(end 0.12065 -0.2794)
			(stroke
				(width 0.1)
				(type default)
			)
			(layer "B.Fab")
		)
		(fp_line
			(start 0.12065 -0.2794)
			(end -0.12065 -0.2794)
			(stroke
				(width 0.1)
				(type default)
			)
			(layer "B.Fab")
		)
		(fp_line
			(start 0.12065 0.2794)
			(end 0.12065 0.3048)
			(stroke
				(width 0.1)
				(type default)
			)
			(layer "B.Fab")
		)
		(fp_line
			(start 0.12065 0.3048)
			(end 0.67945 0.3048)
			(stroke
				(width 0.1)
				(type default)
			)
			(layer "B.Fab")
		)
		(fp_line
			(start 0.67945 -0.305054)
			(end 0.12065 -0.305054)
			(stroke
				(width 0.1)
				(type default)
			)
			(layer "B.Fab")
		)
		(fp_line
			(start 0.67945 0.3048)
			(end 0.67945 -0.305054)
			(stroke
				(width 0.1)
				(type default)
			)
			(layer "B.Fab")
		)
		(pad "1" smd circle
			(at 0.40005 0 180)
			(size 0 0)
			(layers "B.Cu" "B.Mask" "B.Paste")
			(net "PVDDCR_SOC_P0")
		)
		(pad "2" smd circle
			(at -0.40005 0 180)
			(size 0 0)
			(layers "B.Cu" "B.Mask" "B.Paste")
			(net "GND")
		)
	)
	(footprint ""
		(layer "B.Cu")
		(at 373.202454 -266.00531)
		(property "Reference" "C2639"
			(at 0 0 0)
			(layer "B.SilkS")
			(hide yes)
			(effects
				(font
					(size 1.27 1.27)
				)
				(justify mirror)
			)
		)
		(property "Value" ""
			(at 0 0 0)
			(layer "B.Fab")
			(effects
				(font
					(size 1.27 1.27)
				)
				(justify mirror)
			)
		)
		(duplicate_pad_numbers_are_jumpers no)
		(fp_line
			(start -0.7874 -0.4064)
			(end -0.7874 0.4064)
			(stroke
				(width 0.1524)
				(type default)
			)
			(layer "B.SilkS")
		)
		(fp_line
			(start -0.7874 0.4064)
			(end 0.7874 0.4064)
			(stroke
				(width 0.1524)
				(type default)
			)
			(layer "B.SilkS")
		)
		(fp_line
			(start 0.7874 -0.4064)
			(end -0.7874 -0.4064)
			(stroke
				(width 0.1524)
				(type default)
			)
			(layer "B.SilkS")
		)
		(fp_line
			(start 0.7874 0.4064)
			(end 0.7874 -0.4064)
			(stroke
				(width 0.1524)
				(type default)
			)
			(layer "B.SilkS")
		)
		(fp_line
			(start -0.67945 -0.3048)
			(end -0.67945 0.3048)
			(stroke
				(width 0.1)
				(type default)
			)
			(layer "B.Fab")
		)
		(fp_line
			(start -0.67945 0.3048)
			(end -0.120396 0.3048)
			(stroke
				(width 0.1)
				(type default)
			)
			(layer "B.Fab")
		)
		(fp_line
			(start -0.12065 -0.3048)
			(end -0.67945 -0.3048)
			(stroke
				(width 0.1)
				(type default)
			)
			(layer "B.Fab")
		)
		(fp_line
			(start -0.12065 -0.2794)
			(end -0.12065 -0.3048)
			(stroke
				(width 0.1)
				(type default)
			)
			(layer "B.Fab")
		)
		(fp_line
			(start -0.120396 0.2794)
			(end 0.12065 0.2794)
			(stroke
				(width 0.1)
				(type default)
			)
			(layer "B.Fab")
		)
		(fp_line
			(start -0.120396 0.3048)
			(end -0.120396 0.2794)
			(stroke
				(width 0.1)
				(type default)
			)
			(layer "B.Fab")
		)
		(fp_line
			(start 0.12065 -0.305054)
			(end 0.12065 -0.2794)
			(stroke
				(width 0.1)
				(type default)
			)
			(layer "B.Fab")
		)
		(fp_line
			(start 0.12065 -0.2794)
			(end -0.12065 -0.2794)
			(stroke
				(width 0.1)
				(type default)
			)
			(layer "B.Fab")
		)
		(fp_line
			(start 0.12065 0.2794)
			(end 0.12065 0.3048)
			(stroke
				(width 0.1)
				(type default)
			)
			(layer "B.Fab")
		)
		(fp_line
			(start 0.12065 0.3048)
			(end 0.67945 0.3048)
			(stroke
				(width 0.1)
				(type default)
			)
			(layer "B.Fab")
		)
		(fp_line
			(start 0.67945 -0.305054)
			(end 0.12065 -0.305054)
			(stroke
				(width 0.1)
				(type default)
			)
			(layer "B.Fab")
		)
		(fp_line
			(start 0.67945 0.3048)
			(end 0.67945 -0.305054)
			(stroke
				(width 0.1)
				(type default)
			)
			(layer "B.Fab")
		)
		(pad "1" smd circle
			(at 0.40005 0 180)
			(size 0 0)
			(layers "B.Cu" "B.Mask" "B.Paste")
			(net "PVDD11_S3_P0")
		)
		(pad "2" smd circle
			(at -0.40005 0 180)
			(size 0 0)
			(layers "B.Cu" "B.Mask" "B.Paste")
			(net "GND")
		)
	)
	(footprint ""
		(layer "B.Cu")
		(at 160.69183 -17.79016)
		(property "Reference" "R4150"
			(at 0 0 0)
			(layer "B.SilkS")
			(hide yes)
			(effects
				(font
					(size 1.27 1.27)
				)
				(justify mirror)
			)
		)
		(property "Value" ""
			(at 0 0 0)
			(layer "B.Fab")
			(effects
				(font
					(size 1.27 1.27)
				)
				(justify mirror)
			)
		)
		(duplicate_pad_numbers_are_jumpers no)
		(fp_line
			(start -0.7874 -0.4064)
			(end -0.7874 0.4064)
			(stroke
				(width 0.1524)
				(type default)
			)
			(layer "B.SilkS")
		)
		(fp_line
			(start -0.7874 0.4064)
			(end 0.7874 0.4064)
			(stroke
				(width 0.1524)
				(type default)
			)
			(layer "B.SilkS")
		)
		(fp_line
			(start 0.7874 -0.4064)
			(end -0.7874 -0.4064)
			(stroke
				(width 0.1524)
				(type default)
			)
			(layer "B.SilkS")
		)
		(fp_line
			(start 0.7874 0.4064)
			(end 0.7874 -0.4064)
			(stroke
				(width 0.1524)
				(type default)
			)
			(layer "B.SilkS")
		)
		(fp_line
			(start -0.67945 -0.3048)
			(end -0.67945 0.3048)
			(stroke
				(width 0.1)
				(type default)
			)
			(layer "B.Fab")
		)
		(fp_line
			(start -0.67945 0.3048)
			(end -0.120396 0.3048)
			(stroke
				(width 0.1)
				(type default)
			)
			(layer "B.Fab")
		)
		(fp_line
			(start -0.12065 -0.3048)
			(end -0.67945 -0.3048)
			(stroke
				(width 0.1)
				(type default)
			)
			(layer "B.Fab")
		)
		(fp_line
			(start -0.12065 -0.2794)
			(end -0.12065 -0.3048)
			(stroke
				(width 0.1)
				(type default)
			)
			(layer "B.Fab")
		)
		(fp_line
			(start -0.120396 0.2794)
			(end 0.12065 0.2794)
			(stroke
				(width 0.1)
				(type default)
			)
			(layer "B.Fab")
		)
		(fp_line
			(start -0.120396 0.3048)
			(end -0.120396 0.2794)
			(stroke
				(width 0.1)
				(type default)
			)
			(layer "B.Fab")
		)
		(fp_line
			(start 0.12065 -0.305054)
			(end 0.12065 -0.2794)
			(stroke
				(width 0.1)
				(type default)
			)
			(layer "B.Fab")
		)
		(fp_line
			(start 0.12065 -0.2794)
			(end -0.12065 -0.2794)
			(stroke
				(width 0.1)
				(type default)
			)
			(layer "B.Fab")
		)
		(fp_line
			(start 0.12065 0.2794)
			(end 0.12065 0.3048)
			(stroke
				(width 0.1)
				(type default)
			)
			(layer "B.Fab")
		)
		(fp_line
			(start 0.12065 0.3048)
			(end 0.67945 0.3048)
			(stroke
				(width 0.1)
				(type default)
			)
			(layer "B.Fab")
		)
		(fp_line
			(start 0.67945 -0.305054)
			(end 0.12065 -0.305054)
			(stroke
				(width 0.1)
				(type default)
			)
			(layer "B.Fab")
		)
		(fp_line
			(start 0.67945 0.3048)
			(end 0.67945 -0.305054)
			(stroke
				(width 0.1)
				(type default)
			)
			(layer "B.Fab")
		)
		(pad "1" smd circle
			(at 0.40005 0 180)
			(size 0 0)
			(layers "B.Cu" "B.Mask" "B.Paste")
			(net "SMB_1_PLD_3V3AUX_SDA")
		)
		(pad "2" smd circle
			(at -0.40005 0 180)
			(size 0 0)
			(layers "B.Cu" "B.Mask" "B.Paste")
			(net "SMB_1_PLD_3V3AUX_SDA_R1")
		)
	)
	(footprint ""
		(layer "B.Cu")
		(at 184.332372 -113.462816 90)
		(property "Reference" "C359"
			(at 0 0 90)
			(layer "B.SilkS")
			(hide yes)
			(effects
				(font
					(size 1.27 1.27)
				)
				(justify mirror)
			)
		)
		(property "Value" ""
			(at 0 0 90)
			(layer "B.Fab")
			(effects
				(font
					(size 1.27 1.27)
				)
				(justify mirror)
			)
		)
		(duplicate_pad_numbers_are_jumpers no)
		(fp_line
			(start 0.69215 -0.2921)
			(end -0.69215 -0.2921)
			(stroke
				(width 0.1524)
				(type default)
			)
			(layer "B.SilkS")
		)
		(fp_line
			(start -0.69215 -0.2921)
			(end -0.69215 0.2921)
			(stroke
				(width 0.1524)
				(type default)
			)
			(layer "B.SilkS")
		)
		(fp_line
			(start 0.69215 0.2921)
			(end 0.69215 -0.2921)
			(stroke
				(width 0.1524)
				(type default)
			)
			(layer "B.SilkS")
		)
		(fp_line
			(start -0.69215 0.2921)
			(end 0.69215 0.2921)
			(stroke
				(width 0.1524)
				(type default)
			)
			(layer "B.SilkS")
		)
		(fp_line
			(start 0.51435 -0.2794)
			(end -0.51435 -0.2794)
			(stroke
				(width 0.1)
				(type default)
			)
			(layer "B.Fab")
		)
		(fp_line
			(start -0.51435 -0.2794)
			(end -0.51435 0.2794)
			(stroke
				(width 0.1)
				(type default)
			)
			(layer "B.Fab")
		)
		(fp_line
			(start 0.51435 0.2794)
			(end 0.51435 -0.2794)
			(stroke
				(width 0.1)
				(type default)
			)
			(layer "B.Fab")
		)
		(fp_line
			(start -0.51435 0.2794)
			(end 0.51435 0.2794)
			(stroke
				(width 0.1)
				(type default)
			)
			(layer "B.Fab")
		)
		(pad "1" smd circle
			(at 0.40005 0 270)
			(size 0 0)
			(layers "B.Cu" "B.Mask" "B.Paste")
			(net "P3V3_AUX")
		)
		(pad "2" smd circle
			(at -0.40005 0 270)
			(size 0 0)
			(layers "B.Cu" "B.Mask" "B.Paste")
			(net "GND")
		)
		(zone
			(layer "B.Cu")
			(hatch none 0.5)
			(connect_pads
				(clearance 0)
			)
			(min_thickness 0.25)
			(keepout
				(tracks not_allowed)
				(vias allowed)
				(pads allowed)
				(copperpour not_allowed)
				(footprints allowed)
			)
			(placement
				(enabled no)
				(sheetname "")
			)
			(fill
				(thermal_gap 0.5)
				(thermal_bridge_width 0.5)
				(island_removal_mode 0)
			)
			(polygon
				(pts
					(xy 184.186322 -113.362486) (xy 184.186322 -113.561876) (xy 184.244488 -113.653316) (xy 184.420002 -113.653316)
					(xy 184.478168 -113.561876) (xy 184.478168 -113.362486) (xy 184.420002 -113.272316) (xy 184.244742 -113.272316)
				)
			)
		)
	)
	(footprint ""
		(layer "B.Cu")
		(at 314.965588 -2.537206 180)
		(property "Reference" "J115"
			(at 4.61264 -1.551178 270)
			(unlocked yes)
			(layer "B.SilkS")
			(effects
				(font
					(size 0.7874 0.5842)
					(thickness 0.1524)
				)
				(justify left mirror)
			)
		)
		(property "Value" ""
			(at 0 0 0)
			(layer "B.Fab")
			(effects
				(font
					(size 1.27 1.27)
				)
				(justify mirror)
			)
		)
		(duplicate_pad_numbers_are_jumpers no)
		(fp_line
			(start 1.2192 2.06756)
			(end 1.2192 -2.06756)
			(stroke
				(width 0.1524)
				(type default)
			)
			(layer "B.SilkS")
		)
		(fp_line
			(start 1.2192 -2.06756)
			(end -1.2192 -2.06756)
			(stroke
				(width 0.1524)
				(type default)
			)
			(layer "B.SilkS")
		)
		(fp_line
			(start -1.2192 2.06756)
			(end 1.2192 2.06756)
			(stroke
				(width 0.1524)
				(type default)
			)
			(layer "B.SilkS")
		)
		(fp_line
			(start -1.2192 -2.06756)
			(end -1.2192 2.06756)
			(stroke
				(width 0.1524)
				(type default)
			)
			(layer "B.SilkS")
		)
		(pad "" np_thru_hole circle
			(at -3.4671 -1.27 90)
			(size 1.0414 1.0414)
			(drill 1.0414)
			(layers "*.Cu" "*.Mask")
			(clearance 0.381)
			(thermal_gap 0.381)
		)
		(pad "" np_thru_hole circle
			(at -3.4671 1.27 90)
			(size 1.0414 1.0414)
			(drill 1.0414)
			(layers "*.Cu" "*.Mask")
			(clearance 0.381)
			(thermal_gap 0.381)
		)
		(pad "" np_thru_hole circle
			(at 2.8829 -1.27 90)
			(size 1.0414 1.0414)
			(drill 1.0414)
			(layers "*.Cu" "*.Mask")
			(clearance 0.381)
			(thermal_gap 0.381)
		)
		(pad "" np_thru_hole circle
			(at 2.8829 1.27 90)
			(size 1.0414 1.0414)
			(drill 1.0414)
			(layers "*.Cu" "*.Mask")
			(clearance 0.381)
			(thermal_gap 0.381)
		)
		(pad "1" smd rect
			(at -0.8255 -0.249936 90)
			(size 0.3048 0.508)
			(layers "B.Cu" "B.Mask" "B.Paste")
			(net "DELTA_L_85_5INCH_IN6_DP")
		)
		(pad "2" smd rect
			(at -0.8255 0.249936 90)
			(size 0.3048 0.508)
			(layers "B.Cu" "B.Mask" "B.Paste")
			(net "DELTA_L_85_5INCH_IN6_DN")
		)
		(pad "3" smd circle
			(at 0 0)
			(size 0 0)
			(layers "B.Cu" "B.Mask" "B.Paste")
			(net "DELTA_L_GND_1")
		)
		(zone
			(layers "F.Cu" "B.Cu" "In1.Cu" "In2.Cu" "In3.Cu" "In4.Cu" "In5.Cu" "In6.Cu"
				"In7.Cu" "In8.Cu" "In9.Cu" "In10.Cu" "In11.Cu" "In12.Cu" "In13.Cu" "In14.Cu"
				"In15.Cu" "In16.Cu"
			)
			(hatch none 0.5)
			(connect_pads
				(clearance 0)
			)
			(min_thickness 0.25)
			(keepout
				(tracks not_allowed)
				(vias allowed)
				(pads allowed)
				(copperpour not_allowed)
				(footprints allowed)
			)
			(placement
				(enabled no)
				(sheetname "")
			)
			(fill
				(thermal_gap 0.5)
				(thermal_bridge_width 0.5)
				(island_removal_mode 0)
			)
			(polygon
				(pts
					(arc
						(start 313.009788 -3.807206)
						(mid 311.155588 -3.807206)
						(end 313.009788 -3.807206)
					)
				)
			)
		)
		(zone
			(layers "F.Cu" "B.Cu" "In1.Cu" "In2.Cu" "In3.Cu" "In4.Cu" "In5.Cu" "In6.Cu"
				"In7.Cu" "In8.Cu" "In9.Cu" "In10.Cu" "In11.Cu" "In12.Cu" "In13.Cu" "In14.Cu"
				"In15.Cu" "In16.Cu"
			)
			(hatch none 0.5)
			(connect_pads
				(clearance 0)
			)
			(min_thickness 0.25)
			(keepout
				(tracks not_allowed)
				(vias allowed)
				(pads allowed)
				(copperpour not_allowed)
				(footprints allowed)
			)
			(placement
				(enabled no)
				(sheetname "")
			)
			(fill
				(thermal_gap 0.5)
				(thermal_bridge_width 0.5)
				(island_removal_mode 0)
			)
			(polygon
				(pts
					(arc
						(start 313.009788 -1.267206)
						(mid 311.155588 -1.267206)
						(end 313.009788 -1.267206)
					)
				)
			)
		)
		(zone
			(layers "F.Cu" "B.Cu" "In1.Cu" "In2.Cu" "In3.Cu" "In4.Cu" "In5.Cu" "In6.Cu"
				"In7.Cu" "In8.Cu" "In9.Cu" "In10.Cu" "In11.Cu" "In12.Cu" "In13.Cu" "In14.Cu"
				"In15.Cu" "In16.Cu"
			)
			(hatch none 0.5)
			(connect_pads
				(clearance 0)
			)
			(min_thickness 0.25)
			(keepout
				(tracks not_allowed)
				(vias allowed)
				(pads allowed)
				(copperpour not_allowed)
				(footprints allowed)
			)
			(placement
				(enabled no)
				(sheetname "")
			)
			(fill
				(thermal_gap 0.5)
				(thermal_bridge_width 0.5)
				(island_removal_mode 0)
			)
			(polygon
				(pts
					(arc
						(start 319.359788 -3.807206)
						(mid 317.505588 -3.807206)
						(end 319.359788 -3.807206)
					)
				)
			)
		)
		(zone
			(layers "F.Cu" "B.Cu" "In1.Cu" "In2.Cu" "In3.Cu" "In4.Cu" "In5.Cu" "In6.Cu"
				"In7.Cu" "In8.Cu" "In9.Cu" "In10.Cu" "In11.Cu" "In12.Cu" "In13.Cu" "In14.Cu"
				"In15.Cu" "In16.Cu"
			)
			(hatch none 0.5)
			(connect_pads
				(clearance 0)
			)
			(min_thickness 0.25)
			(keepout
				(tracks not_allowed)
				(vias allowed)
				(pads allowed)
				(copperpour not_allowed)
				(footprints allowed)
			)
			(placement
				(enabled no)
				(sheetname "")
			)
			(fill
				(thermal_gap 0.5)
				(thermal_bridge_width 0.5)
				(island_removal_mode 0)
			)
			(polygon
				(pts
					(arc
						(start 319.359788 -1.267206)
						(mid 317.505588 -1.267206)
						(end 319.359788 -1.267206)
					)
				)
			)
		)
		(zone
			(layer "B.Cu")
			(hatch none 0.5)
			(connect_pads
				(clearance 0)
			)
			(min_thickness 0.25)
			(keepout
				(tracks not_allowed)
				(vias allowed)
				(pads allowed)
				(copperpour not_allowed)
				(footprints allowed)
			)
			(placement
				(enabled no)
				(sheetname "")
			)
			(fill
				(thermal_gap 0.5)
				(thermal_bridge_width 0.5)
				(island_removal_mode 0)
			)
			(polygon
				(pts
					(xy 316.083188 -1.988566) (xy 316.083188 -2.08407) (xy 315.486288 -2.08407) (xy 315.486288 -2.49047)
					(xy 316.083188 -2.49047) (xy 316.083188 -2.583942) (xy 315.486288 -2.583942) (xy 315.486288 -2.990342)
					(xy 316.083188 -2.990342) (xy 316.083188 -3.085846) (xy 315.384688 -3.085846) (xy 315.384688 -1.988566)
				)
			)
		)
	)
)
